# S9S_MB_2U (Grand Teton) — schematic netlist excerpt (pin names and nets, part order shuffled) for the footprints in the layout excerpt that follows; sources: Cadence DE-HDL packaged netlist, KiCad conversion of 03242023_DA0F0TMBIJ0_F0T_Motherboard_J_brd_V01_OCP.brd

C1238  Q_CAP  0.1UF 25V 10% X7R  pkg 0402  page 153 : A = P3V3_OCP_SFF ; B = GND
C390  Q_CAP  47UF 4V 20% X6S  pkg C0805  page 76 : A = PVCCIN_CPU0 ; B = GND
R6  Q_RES  100 1% CHIP  pkg 0402LF  page 13 : A = JTAG_DBP_CPU_QS_GTL_TMS ; B = JTAG_DBP_CPU0_QS_GTL_R_TMS

(kicad_pcb
	(version 20260206)
	(generator "pcbnew")
	(generator_version "10.0")
	(general
		(thickness 1.6)
		(legacy_teardrops no)
	)
	(paper "A4")
	(title_block
		(title "03242023_DA0F0TMBIJ0_F0T_Motherboard_J_brd_V01_OCP.brd")
		(comment 1 "Grand Teton / footprints 5562-5564 of 6105")
	)
	(layers
		(0 "F.Cu" signal "TOP")
		(4 "In1.Cu" signal "GND")
		(6 "In2.Cu" signal "IN1")
		(8 "In3.Cu" signal "GND1")
		(10 "In4.Cu" signal "IN2")
		(12 "In5.Cu" signal "GND2")
		(14 "In6.Cu" signal "IN3")
		(16 "In7.Cu" signal "GND3")
		(18 "In8.Cu" signal "VCC")
		(20 "In9.Cu" signal "VCC1")
		(22 "In10.Cu" signal "GND4")
		(24 "In11.Cu" signal "IN4")
		(26 "In12.Cu" signal "GND5")
		(28 "In13.Cu" signal "IN5")
		(30 "In14.Cu" signal "GND6")
		(32 "In15.Cu" signal "IN6")
		(34 "In16.Cu" signal "GND7")
		(2 "B.Cu" signal "BOTTOM")
		(9 "F.Adhes" user "F.Adhesive")
		(11 "B.Adhes" user "B.Adhesive")
		(13 "F.Paste" user "Package Geometry/Pastemask Top")
		(15 "B.Paste" user "Package Geometry/Pastemask Bottom")
		(5 "F.SilkS" user "Ref Des/Silkscreen Top")
		(7 "B.SilkS" user "Ref Des/Silkscreen Bottom")
		(1 "F.Mask" user "Board Geometry/Soldermask Top")
		(3 "B.Mask" user "Board Geometry/Soldermask Bottom")
		(17 "Dwgs.User" user "User.Drawings")
		(19 "Cmts.User" user "User.Comments")
		(21 "Eco1.User" user "User.Eco1")
		(23 "Eco2.User" user "User.Eco2")
		(25 "Edge.Cuts" user "Board Geometry/Outline")
		(27 "Margin" user)
		(31 "F.CrtYd" user "Package Geometry/Place Bound Top")
		(29 "B.CrtYd" user "Package Geometry/Place Bound Bottom")
		(35 "F.Fab" user "Ref Des/Assembly Top")
		(33 "B.Fab" user "Ref Des/Assembly Bottom")
	)
	(footprint ""
		(layer "B.Cu")
		(at 435.549802 -12.104116 180)
		(property "Reference" "C1238"
			(at 0 0 0)
			(layer "B.SilkS")
			(hide yes)
			(effects
				(font
					(size 1.27 1.27)
				)
				(justify mirror)
			)
		)
		(property "Value" ""
			(at 0 0 0)
			(layer "B.Fab")
			(effects
				(font
					(size 1.27 1.27)
				)
				(justify mirror)
			)
		)
		(duplicate_pad_numbers_are_jumpers no)
		(fp_line
			(start 0.7874 0.4064)
			(end 0.7874 -0.4064)
			(stroke
				(width 0.1524)
				(type default)
			)
			(layer "B.SilkS")
		)
		(fp_line
			(start 0.7874 -0.4064)
			(end -0.7874 -0.4064)
			(stroke
				(width 0.1524)
				(type default)
			)
			(layer "B.SilkS")
		)
		(fp_line
			(start -0.7874 0.4064)
			(end 0.7874 0.4064)
			(stroke
				(width 0.1524)
				(type default)
			)
			(layer "B.SilkS")
		)
		(fp_line
			(start -0.7874 -0.4064)
			(end -0.7874 0.4064)
			(stroke
				(width 0.1524)
				(type default)
			)
			(layer "B.SilkS")
		)
		(fp_line
			(start 0.67945 0.3048)
			(end 0.67945 -0.305054)
			(stroke
				(width 0.1)
				(type default)
			)
			(layer "B.Fab")
		)
		(fp_line
			(start 0.67945 -0.305054)
			(end 0.12065 -0.305054)
			(stroke
				(width 0.1)
				(type default)
			)
			(layer "B.Fab")
		)
		(fp_line
			(start 0.12065 0.3048)
			(end 0.67945 0.3048)
			(stroke
				(width 0.1)
				(type default)
			)
			(layer "B.Fab")
		)
		(fp_line
			(start 0.12065 0.2794)
			(end 0.12065 0.3048)
			(stroke
				(width 0.1)
				(type default)
			)
			(layer "B.Fab")
		)
		(fp_line
			(start 0.12065 -0.2794)
			(end -0.12065 -0.2794)
			(stroke
				(width 0.1)
				(type default)
			)
			(layer "B.Fab")
		)
		(fp_line
			(start 0.12065 -0.305054)
			(end 0.12065 -0.2794)
			(stroke
				(width 0.1)
				(type default)
			)
			(layer "B.Fab")
		)
		(fp_line
			(start -0.120396 0.3048)
			(end -0.120396 0.2794)
			(stroke
				(width 0.1)
				(type default)
			)
			(layer "B.Fab")
		)
		(fp_line
			(start -0.120396 0.2794)
			(end 0.12065 0.2794)
			(stroke
				(width 0.1)
				(type default)
			)
			(layer "B.Fab")
		)
		(fp_line
			(start -0.12065 -0.2794)
			(end -0.12065 -0.3048)
			(stroke
				(width 0.1)
				(type default)
			)
			(layer "B.Fab")
		)
		(fp_line
			(start -0.12065 -0.3048)
			(end -0.67945 -0.3048)
			(stroke
				(width 0.1)
				(type default)
			)
			(layer "B.Fab")
		)
		(fp_line
			(start -0.67945 0.3048)
			(end -0.120396 0.3048)
			(stroke
				(width 0.1)
				(type default)
			)
			(layer "B.Fab")
		)
		(fp_line
			(start -0.67945 -0.3048)
			(end -0.67945 0.3048)
			(stroke
				(width 0.1)
				(type default)
			)
			(layer "B.Fab")
		)
		(pad "1" smd circle
			(at 0.40005 0)
			(size 0 0)
			(layers "B.Cu" "B.Mask" "B.Paste")
			(net "P3V3_OCP_SFF")
		)
		(pad "2" smd circle
			(at -0.40005 0)
			(size 0 0)
			(layers "B.Cu" "B.Mask" "B.Paste")
			(net "GND")
		)
	)
	(footprint ""
		(layer "B.Cu")
		(at 326.338438 -188.89599 -90)
		(property "Reference" "R6"
			(at 0 0 90)
			(layer "B.SilkS")
			(hide yes)
			(effects
				(font
					(size 1.27 1.27)
				)
				(justify mirror)
			)
		)
		(property "Value" ""
			(at 0 0 90)
			(layer "B.Fab")
			(effects
				(font
					(size 1.27 1.27)
				)
				(justify mirror)
			)
		)
		(duplicate_pad_numbers_are_jumpers no)
		(fp_line
			(start -0.7874 0.4064)
			(end 0.7874 0.4064)
			(stroke
				(width 0.1524)
				(type default)
			)
			(layer "B.SilkS")
		)
		(fp_line
			(start 0.7874 0.4064)
			(end 0.7874 -0.4064)
			(stroke
				(width 0.1524)
				(type default)
			)
			(layer "B.SilkS")
		)
		(fp_line
			(start -0.7874 -0.4064)
			(end -0.7874 0.4064)
			(stroke
				(width 0.1524)
				(type default)
			)
			(layer "B.SilkS")
		)
		(fp_line
			(start 0.7874 -0.4064)
			(end -0.7874 -0.4064)
			(stroke
				(width 0.1524)
				(type default)
			)
			(layer "B.SilkS")
		)
		(fp_line
			(start -0.67945 0.3048)
			(end -0.120396 0.3048)
			(stroke
				(width 0.1)
				(type default)
			)
			(layer "B.Fab")
		)
		(fp_line
			(start -0.120396 0.3048)
			(end -0.120396 0.2794)
			(stroke
				(width 0.1)
				(type default)
			)
			(layer "B.Fab")
		)
		(fp_line
			(start 0.12065 0.3048)
			(end 0.67945 0.3048)
			(stroke
				(width 0.1)
				(type default)
			)
			(layer "B.Fab")
		)
		(fp_line
			(start 0.67945 0.3048)
			(end 0.67945 -0.305054)
			(stroke
				(width 0.1)
				(type default)
			)
			(layer "B.Fab")
		)
		(fp_line
			(start -0.120396 0.2794)
			(end 0.12065 0.2794)
			(stroke
				(width 0.1)
				(type default)
			)
			(layer "B.Fab")
		)
		(fp_line
			(start 0.12065 0.2794)
			(end 0.12065 0.3048)
			(stroke
				(width 0.1)
				(type default)
			)
			(layer "B.Fab")
		)
		(fp_line
			(start -0.12065 -0.2794)
			(end -0.12065 -0.3048)
			(stroke
				(width 0.1)
				(type default)
			)
			(layer "B.Fab")
		)
		(fp_line
			(start 0.12065 -0.2794)
			(end -0.12065 -0.2794)
			(stroke
				(width 0.1)
				(type default)
			)
			(layer "B.Fab")
		)
		(fp_line
			(start -0.67945 -0.3048)
			(end -0.67945 0.3048)
			(stroke
				(width 0.1)
				(type default)
			)
			(layer "B.Fab")
		)
		(fp_line
			(start -0.12065 -0.3048)
			(end -0.67945 -0.3048)
			(stroke
				(width 0.1)
				(type default)
			)
			(layer "B.Fab")
		)
		(fp_line
			(start 0.12065 -0.305054)
			(end 0.12065 -0.2794)
			(stroke
				(width 0.1)
				(type default)
			)
			(layer "B.Fab")
		)
		(fp_line
			(start 0.67945 -0.305054)
			(end 0.12065 -0.305054)
			(stroke
				(width 0.1)
				(type default)
			)
			(layer "B.Fab")
		)
		(pad "1" smd circle
			(at 0.40005 0 90)
			(size 0 0)
			(layers "B.Cu" "B.Mask" "B.Paste")
			(net "JTAG_DBP_CPU_QS_GTL_TMS")
		)
		(pad "2" smd circle
			(at -0.40005 0 90)
			(size 0 0)
			(layers "B.Cu" "B.Mask" "B.Paste")
			(net "JTAG_DBP_CPU0_QS_GTL_R_TMS")
		)
	)
	(footprint ""
		(layer "B.Cu")
		(at 356.785418 -296.054526 180)
		(property "Reference" "C390"
			(at 0 0 0)
			(layer "B.SilkS")
			(hide yes)
			(effects
				(font
					(size 1.27 1.27)
				)
				(justify mirror)
			)
		)
		(property "Value" ""
			(at 0 0 0)
			(layer "B.Fab")
			(effects
				(font
					(size 1.27 1.27)
				)
				(justify mirror)
			)
		)
		(duplicate_pad_numbers_are_jumpers no)
		(fp_line
			(start 1.524 0.762)
			(end 1.524 -0.762)
			(stroke
				(width 0.1524)
				(type default)
			)
			(layer "B.SilkS")
		)
		(fp_line
			(start 1.524 -0.762)
			(end -1.524 -0.762)
			(stroke
				(width 0.1524)
				(type default)
			)
			(layer "B.SilkS")
		)
		(fp_line
			(start -1.524 0.762)
			(end 1.524 0.762)
			(stroke
				(width 0.1524)
				(type default)
			)
			(layer "B.SilkS")
		)
		(fp_line
			(start -1.524 -0.762)
			(end -1.524 0.762)
			(stroke
				(width 0.1524)
				(type default)
			)
			(layer "B.SilkS")
		)
		(fp_line
			(start 1.1049 0.724916)
			(end -1.1049 0.724916)
			(stroke
				(width 0.1)
				(type default)
			)
			(layer "B.Fab")
		)
		(fp_line
			(start 1.1049 -0.724916)
			(end 1.1049 0.724916)
			(stroke
				(width 0.1)
				(type default)
			)
			(layer "B.Fab")
		)
		(fp_line
			(start -1.1049 0.724916)
			(end -1.1049 -0.724916)
			(stroke
				(width 0.1)
				(type default)
			)
			(layer "B.Fab")
		)
		(fp_line
			(start -1.1049 -0.724916)
			(end 1.1049 -0.724916)
			(stroke
				(width 0.1)
				(type default)
			)
			(layer "B.Fab")
		)
		(pad "1" smd rect
			(at 0.889 0 180)
			(size 1.016 1.27)
			(layers "B.Cu" "B.Mask" "B.Paste")
			(net "PVCCIN_CPU0")
		)
		(pad "2" smd rect
			(at -0.889 0 180)
			(size 1.016 1.27)
			(layers "B.Cu" "B.Mask" "B.Paste")
			(net "GND")
		)
	)
)
